;LEADER: 12 
;HEADER: 
;CODE  : ASCII 
;FILE  : R4006-B0001-02_R01-bd-10-9.drl for backdrilling ... from layer BOTTOM to layer L09_GND4
;DESIGN: R4006-B0001-02_R01.brd
;MUST-NOT-CUT-LAYER = L08_SIG2,  MAX_DRILL_DEPTH = 10.40 MILS,  MFG_STUB_LENGTH = 0.00 MILS
;T11 BackdrillSize 1. = 16.000000 Tolerance = +0.000000/-0.000000 NON_PLATED MILS Quantity = 26
%
G90
T11
X0000107300Y0000382500
X0000070300Y0000357500
X0000073500Y0000357500
X0000110500Y0000382500
X0000337500Y0000119400
X0000337500Y0000116200
X0000362500Y0000092000
X0000365700Y0000092000
X0000354664Y0000104707
X0000351464Y0000104707
X0000344999Y0000108500
X0000341799Y0000108500
X0000399005Y0000146942
X0000395067Y0000146942
X0000391130Y0000143005
X0000387193Y0000143005
X0000399005Y0000154816
X0000395067Y0000154816
X0000391130Y0000150879
X0000387193Y0000150879
X0000469870Y0000146942
X0000473807Y0000146942
X0000473807Y0000139067
X0000473807Y0000135130
X0000619961Y0000227674
X0000619961Y0000224474
M30
